(kicad_pcb
	(version 20260206)
	(generator "pcbnew")
	(generator_version "10.0")
	(general
		(thickness 1.6)
		(legacy_teardrops no)
	)
	(paper "A4")
	(title_block
		(title "Wiwynn_Tioga_Pass_MB.brd")
		(comment 1 "Tioga Pass / footprints 3857-3863 of 4770")
	)
	(layers
		(0 "F.Cu" signal "TOP")
		(4 "In1.Cu" signal "L2GND")
		(6 "In2.Cu" signal "L3")
		(8 "In3.Cu" signal "L4GND")
		(10 "In4.Cu" signal "L5")
		(12 "In5.Cu" signal "L6GND")
		(14 "In6.Cu" signal "L7VCC")
		(16 "In7.Cu" signal "L8VCC")
		(18 "In8.Cu" signal "L9GND")
		(20 "In9.Cu" signal "L10")
		(22 "In10.Cu" signal "L11GND")
		(24 "In11.Cu" signal "L12")
		(26 "In12.Cu" signal "L13GND")
		(2 "B.Cu" signal "BOTTOM")
		(9 "F.Adhes" user "F.Adhesive")
		(11 "B.Adhes" user "B.Adhesive")
		(13 "F.Paste" user "Package Geometry/Pastemask Top")
		(15 "B.Paste" user "Package Geometry/Pastemask Bottom")
		(5 "F.SilkS" user "Ref Des/Silkscreen Top")
		(7 "B.SilkS" user "Ref Des/Silkscreen Bottom")
		(1 "F.Mask" user "Board Geometry/Soldermask Top")
		(3 "B.Mask" user "Board Geometry/Soldermask Bottom")
		(17 "Dwgs.User" user "User.Drawings")
		(19 "Cmts.User" user "User.Comments")
		(21 "Eco1.User" user "User.Eco1")
		(23 "Eco2.User" user "User.Eco2")
		(25 "Edge.Cuts" user "Board Geometry/Outline")
		(27 "Margin" user)
		(31 "F.CrtYd" user "Package Geometry/Place Bound Top")
		(29 "B.CrtYd" user "Package Geometry/Place Bound Bottom")
		(35 "F.Fab" user "Ref Des/Assembly Top")
		(33 "B.Fab" user "Ref Des/Assembly Bottom")
	)
	(footprint ""
		(layer "B.Cu")
		(at 184.20842 2.63652 -90)
		(property "Reference" "C6W11"
			(at -1.47828 0.78994 0)
			(unlocked yes)
			(layer "B.SilkS")
			(effects
				(font
					(size 0.4064 0.254)
					(thickness 0.1524)
				)
				(justify mirror)
			)
		)
		(property "Value" ""
			(at 0 0 90)
			(layer "B.Fab")
			(effects
				(font
					(size 1.27 1.27)
				)
				(justify mirror)
			)
		)
		(duplicate_pad_numbers_are_jumpers no)
		(fp_poly
			(pts
				(xy 0.7239 -0.2159) (xy -0.7239 -0.2159) (xy -0.7239 1.9939) (xy 0.7239 1.9939)
			)
			(stroke
				(width 0)
				(type default)
			)
			(fill no)
			(layer "B.CrtYd")
		)
		(fp_line
			(start -0.7239 1.9939)
			(end -0.7239 -0.2159)
			(stroke
				(width 0.1)
				(type default)
			)
			(layer "B.Fab")
		)
		(fp_line
			(start 0.7239 1.9939)
			(end -0.7239 1.9939)
			(stroke
				(width 0.1)
				(type default)
			)
			(layer "B.Fab")
		)
		(fp_line
			(start -0.7239 -0.2159)
			(end 0.7239 -0.2159)
			(stroke
				(width 0.1)
				(type default)
			)
			(layer "B.Fab")
		)
		(fp_line
			(start 0.7239 -0.2159)
			(end 0.7239 1.9939)
			(stroke
				(width 0.1)
				(type default)
			)
			(layer "B.Fab")
		)
		(pad "1" smd rect
			(at 0 0 90)
			(size 1.27 1.016)
			(layers "B.Cu" "B.Mask" "B.Paste")
			(net "PVTT_ABC")
		)
		(pad "2" smd rect
			(at 0 1.778 90)
			(size 1.27 1.016)
			(layers "B.Cu" "B.Mask" "B.Paste")
			(net "GND")
		)
		(zone
			(layer "B.Cu")
			(hatch none 0.5)
			(connect_pads
				(clearance 0)
			)
			(min_thickness 0.25)
			(keepout
				(tracks not_allowed)
				(vias allowed)
				(pads allowed)
				(copperpour not_allowed)
				(footprints allowed)
			)
			(placement
				(enabled no)
				(sheetname "")
			)
			(fill
				(thermal_gap 0.5)
				(thermal_bridge_width 0.5)
				(island_removal_mode 0)
			)
			(polygon
				(pts
					(xy 183.70042 3.27152) (xy 183.70042 2.00152) (xy 182.93842 2.00152) (xy 182.93842 3.27152)
				)
			)
		)
	)
	(footprint ""
		(layer "B.Cu")
		(at 393.005818 -14.637004)
		(property "Reference" "U32W1"
			(at 0 0 0)
			(layer "B.SilkS")
			(hide yes)
			(effects
				(font
					(size 1.27 1.27)
				)
				(justify mirror)
			)
		)
		(property "Value" "*"
			(at 0.1143 -9.3091 0)
			(unlocked yes)
			(layer "B.Fab")
			(hide yes)
			(effects
				(font
					(size 1.27 1.016)
					(thickness 0.1524)
				)
				(justify mirror)
			)
		)
		(property "Device Type" "TCA9517DGKR-GP_DISCRET-G8-TCA9A"
			(at 0.1143 -10.9093 0)
			(unlocked yes)
			(layer "B.Fab")
			(hide yes)
			(effects
				(font
					(size 1.27 1.016)
					(thickness 0.1524)
				)
				(justify mirror)
			)
		)
		(duplicate_pad_numbers_are_jumpers no)
		(fp_line
			(start -1.0795 -1.016)
			(end 1.9558 -1.016)
			(stroke
				(width 0.1524)
				(type default)
			)
			(layer "B.SilkS")
		)
		(fp_line
			(start -1.0795 1.016)
			(end -1.0795 -1.016)
			(stroke
				(width 0.1524)
				(type default)
			)
			(layer "B.SilkS")
		)
		(fp_line
			(start 1.4478 -0.0381)
			(end 1.9558 0.4699)
			(stroke
				(width 0.1524)
				(type default)
			)
			(layer "B.SilkS")
		)
		(fp_line
			(start 1.778 1.0922)
			(end 1.778 3.048)
			(stroke
				(width 0.508)
				(type default)
			)
			(layer "B.SilkS")
		)
		(fp_line
			(start 1.9558 -1.016)
			(end 1.9558 1.016)
			(stroke
				(width 0.1524)
				(type default)
			)
			(layer "B.SilkS")
		)
		(fp_line
			(start 1.9558 -0.5461)
			(end 1.4478 -0.0381)
			(stroke
				(width 0.1524)
				(type default)
			)
			(layer "B.SilkS")
		)
		(fp_line
			(start 1.9558 1.016)
			(end -1.0795 1.016)
			(stroke
				(width 0.1524)
				(type default)
			)
			(layer "B.SilkS")
		)
		(fp_poly
			(pts
				(xy 1.1557 -1.016) (xy 1.1557 1.016) (xy -1.1557 1.016) (xy -1.1557 -1.016)
			)
			(stroke
				(width 0)
				(type default)
			)
			(fill yes)
			(layer "B.SilkS")
		)
		(fp_rect
			(start 1.4986 2.4511)
			(end -1.4986 -2.4511)
			(stroke
				(width 0)
				(type default)
			)
			(fill no)
			(layer "B.CrtYd")
		)
		(fp_poly
			(pts
				(xy 2.032 3.302) (xy 2.032 -3.302) (xy -2.032 -3.302) (xy -2.032 -2.1209) (xy -1.4986 -2.1209) (xy -1.4986 -2.4511)
				(xy 1.4986 -2.4511) (xy 1.4986 2.4511) (xy -1.4986 2.4511) (xy -1.4986 -2.1082) (xy -2.032 -2.1082)
				(xy -2.032 3.302)
			)
			(stroke
				(width 0)
				(type default)
			)
			(fill no)
			(layer "B.CrtYd")
		)
		(fp_rect
			(start 2.032 3.302)
			(end -2.032 -3.302)
			(stroke
				(width 0)
				(type default)
			)
			(fill no)
			(layer "B.Fab")
		)
		(pad "1" smd rect
			(at 0.97536 2.05486 180)
			(size 0.3556 1.524)
			(layers "B.Cu" "B.Mask" "B.Paste")
			(net "P1V8_M2")
		)
		(pad "2" smd rect
			(at 0.32512 2.05486 180)
			(size 0.3556 1.524)
			(layers "B.Cu" "B.Mask" "B.Paste")
			(net "SMB_M2_SCL_R")
		)
		(pad "3" smd rect
			(at -0.32512 2.05486 180)
			(size 0.3556 1.524)
			(layers "B.Cu" "B.Mask" "B.Paste")
			(net "SMB_M2_SDA_R")
		)
		(pad "4" smd rect
			(at -0.97536 2.05486 180)
			(size 0.3556 1.524)
			(layers "B.Cu" "B.Mask" "B.Paste")
			(net "GND")
		)
		(pad "5" smd rect
			(at -0.97536 -2.05486 180)
			(size 0.3556 1.524)
			(layers "B.Cu" "B.Mask" "B.Paste")
			(net "PD_SMB_M2_EN")
		)
		(pad "6" smd rect
			(at -0.32512 -2.05486 180)
			(size 0.3556 1.524)
			(layers "B.Cu" "B.Mask" "B.Paste")
			(net "SMB_OCP_LAN_STBY_LVC3_SDA")
		)
		(pad "7" smd rect
			(at 0.32512 -2.05486 180)
			(size 0.3556 1.524)
			(layers "B.Cu" "B.Mask" "B.Paste")
			(net "SMB_OCP_LAN_STBY_LVC3_SCL")
		)
		(pad "8" smd rect
			(at 0.97536 -2.05486 180)
			(size 0.3556 1.524)
			(layers "B.Cu" "B.Mask" "B.Paste")
			(net "P3V3_STBY")
		)
	)
	(footprint ""
		(layer "B.Cu")
		(at 410.464 -125.476 90)
		(property "Reference" "C2M6"
			(at 0 0 90)
			(layer "B.SilkS")
			(hide yes)
			(effects
				(font
					(size 1.27 1.27)
				)
				(justify mirror)
			)
		)
		(property "Value" ""
			(at 0 0 90)
			(layer "B.Fab")
			(effects
				(font
					(size 1.27 1.27)
				)
				(justify mirror)
			)
		)
		(duplicate_pad_numbers_are_jumpers no)
		(fp_poly
			(pts
				(xy -0.3048 -0.1016) (xy -0.3048 0.9906) (xy 0.3048 0.9906) (xy 0.3048 -0.1016)
			)
			(stroke
				(width 0)
				(type default)
			)
			(fill no)
			(layer "B.CrtYd")
		)
		(fp_line
			(start 0.3048 -0.1016)
			(end 0.3048 0.9906)
			(stroke
				(width 0.1)
				(type default)
			)
			(layer "B.Fab")
		)
		(fp_line
			(start -0.3048 -0.1016)
			(end 0.3048 -0.1016)
			(stroke
				(width 0.1)
				(type default)
			)
			(layer "B.Fab")
		)
		(fp_line
			(start 0.3048 0.9906)
			(end -0.3048 0.9906)
			(stroke
				(width 0.1)
				(type default)
			)
			(layer "B.Fab")
		)
		(fp_line
			(start -0.3048 0.9906)
			(end -0.3048 -0.1016)
			(stroke
				(width 0.1)
				(type default)
			)
			(layer "B.Fab")
		)
		(pad "1" smd rect
			(at 0 0 270)
			(size 0.508 0.508)
			(layers "B.Cu" "B.Mask" "B.Paste")
			(net "P1V05_PCH_STBY")
		)
		(pad "2" smd rect
			(at 0 0.889 270)
			(size 0.508 0.508)
			(layers "B.Cu" "B.Mask" "B.Paste")
			(net "GND")
		)
		(zone
			(layer "B.Cu")
			(hatch none 0.5)
			(connect_pads
				(clearance 0)
			)
			(min_thickness 0.25)
			(keepout
				(tracks allowed)
				(vias not_allowed)
				(pads allowed)
				(copperpour not_allowed)
				(footprints allowed)
			)
			(placement
				(enabled no)
				(sheetname "")
			)
			(fill
				(thermal_gap 0.5)
				(thermal_bridge_width 0.5)
				(island_removal_mode 0)
			)
			(polygon
				(pts
					(xy 410.718 -125.73) (xy 410.718 -125.222) (xy 411.099 -125.222) (xy 411.099 -125.73)
				)
			)
		)
		(zone
			(layer "B.Cu")
			(hatch none 0.5)
			(connect_pads
				(clearance 0)
			)
			(min_thickness 0.25)
			(keepout
				(tracks not_allowed)
				(vias allowed)
				(pads allowed)
				(copperpour not_allowed)
				(footprints allowed)
			)
			(placement
				(enabled no)
				(sheetname "")
			)
			(fill
				(thermal_gap 0.5)
				(thermal_bridge_width 0.5)
				(island_removal_mode 0)
			)
			(polygon
				(pts
					(xy 411.099 -125.73) (xy 411.099 -125.222) (xy 410.718 -125.222) (xy 410.718 -125.73)
				)
			)
		)
	)
	(footprint ""
		(layer "B.Cu")
		(at 9.061958 3.20802)
		(property "Reference" "R12W12"
			(at 0 0 0)
			(layer "B.SilkS")
			(hide yes)
			(effects
				(font
					(size 1.27 1.27)
				)
				(justify mirror)
			)
		)
		(property "Value" "*"
			(at 0 -8.9535 0)
			(unlocked yes)
			(layer "B.Fab")
			(hide yes)
			(effects
				(font
					(size 1.27 1.016)
					(thickness 0.1524)
				)
				(justify mirror)
			)
		)
		(property "Device Type" "665KR5B-1-GP_SMD-RG3-665KR5B-1A"
			(at 0 -10.6299 0)
			(unlocked yes)
			(layer "B.Fab")
			(hide yes)
			(effects
				(font
					(size 1.27 1.016)
					(thickness 0.1524)
				)
				(justify mirror)
			)
		)
		(duplicate_pad_numbers_are_jumpers no)
		(fp_line
			(start -0.889 -1.7018)
			(end -0.889 -0.381)
			(stroke
				(width 0.1524)
				(type default)
			)
			(layer "B.SilkS")
		)
		(fp_line
			(start -0.889 -1.7018)
			(end 0.889 -1.7018)
			(stroke
				(width 0.1524)
				(type default)
			)
			(layer "B.SilkS")
		)
		(fp_line
			(start -0.889 1.7018)
			(end -0.889 -0.508)
			(stroke
				(width 0.1524)
				(type default)
			)
			(layer "B.SilkS")
		)
		(fp_line
			(start 0.889 -1.7018)
			(end 0.889 0.2794)
			(stroke
				(width 0.1524)
				(type default)
			)
			(layer "B.SilkS")
		)
		(fp_line
			(start 0.889 0.0762)
			(end 0.889 1.7018)
			(stroke
				(width 0.1524)
				(type default)
			)
			(layer "B.SilkS")
		)
		(fp_line
			(start 0.889 1.7018)
			(end -0.889 1.7018)
			(stroke
				(width 0.1524)
				(type default)
			)
			(layer "B.SilkS")
		)
		(fp_poly
			(pts
				(xy -0.9652 -1.778) (xy -0.9652 1.778) (xy 0.9652 1.778) (xy 0.9652 -1.778)
			)
			(stroke
				(width 0)
				(type default)
			)
			(fill no)
			(layer "B.CrtYd")
		)
		(fp_rect
			(start 0.9652 1.778)
			(end -0.9652 -1.778)
			(stroke
				(width 0)
				(type default)
			)
			(fill no)
			(layer "B.Fab")
		)
		(pad "1" smd rect
			(at 0 -0.9652 180)
			(size 1.397 1.143)
			(layers "B.Cu" "B.Mask" "B.Paste")
			(net "P12V_NVDIMM_GHJ_D")
		)
		(pad "2" smd rect
			(at 0 0.9652 180)
			(size 1.397 1.143)
			(layers "B.Cu" "B.Mask" "B.Paste")
			(net "VR_PVDDQ_GHJ_VINSEN")
		)
	)
	(footprint ""
		(layer "B.Cu")
		(at 23.114 -79.502 -90)
		(property "Reference" "R9P12"
			(at 0 0 90)
			(layer "B.SilkS")
			(hide yes)
			(effects
				(font
					(size 1.27 1.27)
				)
				(justify mirror)
			)
		)
		(property "Value" ""
			(at 0 0 90)
			(layer "B.Fab")
			(effects
				(font
					(size 1.27 1.27)
				)
				(justify mirror)
			)
		)
		(duplicate_pad_numbers_are_jumpers no)
		(fp_poly
			(pts
				(xy 0.2794 -0.1016) (xy -0.2794 -0.1016) (xy -0.2794 0.9906) (xy 0.2794 0.9906)
			)
			(stroke
				(width 0)
				(type default)
			)
			(fill no)
			(layer "B.CrtYd")
		)
		(fp_line
			(start -0.2794 0.9906)
			(end -0.2794 -0.1016)
			(stroke
				(width 0.1)
				(type default)
			)
			(layer "B.Fab")
		)
		(fp_line
			(start 0.2794 0.9906)
			(end -0.2794 0.9906)
			(stroke
				(width 0.1)
				(type default)
			)
			(layer "B.Fab")
		)
		(fp_line
			(start -0.2794 -0.1016)
			(end 0.2794 -0.1016)
			(stroke
				(width 0.1)
				(type default)
			)
			(layer "B.Fab")
		)
		(fp_line
			(start 0.2794 -0.1016)
			(end 0.2794 0.9906)
			(stroke
				(width 0.1)
				(type default)
			)
			(layer "B.Fab")
		)
		(pad "1" smd rect
			(at 0 0 90)
			(size 0.508 0.508)
			(layers "B.Cu" "B.Mask" "B.Paste")
			(net "A_HSC_INAP")
		)
		(pad "2" smd rect
			(at 0 0.889 90)
			(size 0.508 0.508)
			(layers "B.Cu" "B.Mask" "B.Paste")
			(net "AGND_HSC")
		)
		(zone
			(layer "B.Cu")
			(hatch none 0.5)
			(connect_pads
				(clearance 0)
			)
			(min_thickness 0.25)
			(keepout
				(tracks not_allowed)
				(vias allowed)
				(pads allowed)
				(copperpour not_allowed)
				(footprints allowed)
			)
			(placement
				(enabled no)
				(sheetname "")
			)
			(fill
				(thermal_gap 0.5)
				(thermal_bridge_width 0.5)
				(island_removal_mode 0)
			)
			(polygon
				(pts
					(xy 22.479 -79.248) (xy 22.479 -79.756) (xy 22.86 -79.756) (xy 22.86 -79.248)
				)
			)
		)
		(zone
			(layer "B.Cu")
			(hatch none 0.5)
			(connect_pads
				(clearance 0)
			)
			(min_thickness 0.25)
			(keepout
				(tracks allowed)
				(vias not_allowed)
				(pads allowed)
				(copperpour not_allowed)
				(footprints allowed)
			)
			(placement
				(enabled no)
				(sheetname "")
			)
			(fill
				(thermal_gap 0.5)
				(thermal_bridge_width 0.5)
				(island_removal_mode 0)
			)
			(polygon
				(pts
					(xy 22.86 -79.248) (xy 22.86 -79.756) (xy 22.479 -79.756) (xy 22.479 -79.248)
				)
			)
		)
	)
	(footprint ""
		(layer "B.Cu")
		(at 406.7048 -53.848 -90)
		(property "Reference" "Q1W2"
			(at 0 -0.81788 270)
			(unlocked yes)
			(layer "B.SilkS")
			(effects
				(font
					(size 0.4064 0.254)
					(thickness 0.1524)
				)
				(justify left mirror)
			)
		)
		(property "Value" ""
			(at 0 0 90)
			(layer "B.Fab")
			(effects
				(font
					(size 1.27 1.27)
				)
				(justify mirror)
			)
		)
		(duplicate_pad_numbers_are_jumpers no)
		(fp_circle
			(center 0.848614 -0.6477)
			(end 0.848614 -0.7747)
			(stroke
				(width 0.254)
				(type default)
			)
			(fill no)
			(layer "B.SilkS")
		)
		(fp_poly
			(pts
				(xy -0.21463 -0.450088) (xy -1.56337 -0.450088) (xy -1.56337 1.75006) (xy -0.21463 1.75006)
			)
			(stroke
				(width 0)
				(type default)
			)
			(fill no)
			(layer "B.CrtYd")
		)
		(fp_line
			(start -1.56337 1.75006)
			(end -0.21463 1.75006)
			(stroke
				(width 0.1)
				(type default)
			)
			(layer "B.Fab")
		)
		(fp_line
			(start -0.21463 1.75006)
			(end -0.21463 -0.450088)
			(stroke
				(width 0.1)
				(type default)
			)
			(layer "B.Fab")
		)
		(fp_line
			(start -1.56337 -0.450088)
			(end -1.56337 1.75006)
			(stroke
				(width 0.1)
				(type default)
			)
			(layer "B.Fab")
		)
		(fp_line
			(start -0.21463 -0.450088)
			(end -1.56337 -0.450088)
			(stroke
				(width 0.1)
				(type default)
			)
			(layer "B.Fab")
		)
		(fp_circle
			(center 0.848614 -0.6477)
			(end 0.848614 -0.7747)
			(stroke
				(width 0.254)
				(type default)
			)
			(fill no)
			(layer "B.Fab")
		)
		(pad "1" smd rect
			(at 0 0 90)
			(size 1.016 0.381)
			(layers "B.Cu" "B.Mask" "B.Paste")
			(net "GND")
		)
		(pad "2" smd rect
			(at 0 0.649986 90)
			(size 1.016 0.381)
			(layers "B.Cu" "B.Mask" "B.Paste")
			(net "FM_OCP_MEZZB_PRES_N")
		)
		(pad "3" smd rect
			(at 0 1.299972 90)
			(size 1.016 0.381)
			(layers "B.Cu" "B.Mask" "B.Paste")
			(net "FM_OCP_MEZZB_PRES_1V05_PCH_N")
		)
		(pad "4" smd rect
			(at -1.778 1.299972 90)
			(size 1.016 0.381)
			(layers "B.Cu" "B.Mask" "B.Paste")
			(net "GND")
		)
		(pad "5" smd rect
			(at -1.778 0.649986 90)
			(size 1.016 0.381)
			(layers "B.Cu" "B.Mask" "B.Paste")
			(net "FM_OCP_MEZZB_PRES_LVT3_BMC")
		)
		(pad "6" smd rect
			(at -1.778 0 90)
			(size 1.016 0.381)
			(layers "B.Cu" "B.Mask" "B.Paste")
			(net "FM_OCP_MEZZB_PRES_LVT3_BMC")
		)
	)
	(footprint ""
		(layer "B.Cu")
		(at 372.631716 -59.289442 180)
		(property "Reference" "C3P49"
			(at 0 0 0)
			(layer "B.SilkS")
			(hide yes)
			(effects
				(font
					(size 1.27 1.27)
				)
				(justify mirror)
			)
		)
		(property "Value" ""
			(at 0 0 0)
			(layer "B.Fab")
			(effects
				(font
					(size 1.27 1.27)
				)
				(justify mirror)
			)
		)
		(duplicate_pad_numbers_are_jumpers no)
		(fp_poly
			(pts
				(xy -0.3048 -0.1016) (xy -0.3048 0.9906) (xy 0.3048 0.9906) (xy 0.3048 -0.1016)
			)
			(stroke
				(width 0)
				(type default)
			)
			(fill no)
			(layer "B.CrtYd")
		)
		(fp_line
			(start 0.3048 0.9906)
			(end -0.3048 0.9906)
			(stroke
				(width 0.1)
				(type default)
			)
			(layer "B.Fab")
		)
		(fp_line
			(start 0.3048 -0.1016)
			(end 0.3048 0.9906)
			(stroke
				(width 0.1)
				(type default)
			)
			(layer "B.Fab")
		)
		(fp_line
			(start -0.3048 0.9906)
			(end -0.3048 -0.1016)
			(stroke
				(width 0.1)
				(type default)
			)
			(layer "B.Fab")
		)
		(fp_line
			(start -0.3048 -0.1016)
			(end 0.3048 -0.1016)
			(stroke
				(width 0.1)
				(type default)
			)
			(layer "B.Fab")
		)
		(pad "1" smd rect
			(at 0 0)
			(size 0.508 0.508)
			(layers "B.Cu" "B.Mask" "B.Paste")
			(net "P0V7_GTL2104_VREF_1")
		)
		(pad "2" smd rect
			(at 0 0.889)
			(size 0.508 0.508)
			(layers "B.Cu" "B.Mask" "B.Paste")
			(net "GND")
		)
		(zone
			(layer "B.Cu")
			(hatch none 0.5)
			(connect_pads
				(clearance 0)
			)
			(min_thickness 0.25)
			(keepout
				(tracks not_allowed)
				(vias allowed)
				(pads allowed)
				(copperpour not_allowed)
				(footprints allowed)
			)
			(placement
				(enabled no)
				(sheetname "")
			)
			(fill
				(thermal_gap 0.5)
				(thermal_bridge_width 0.5)
				(island_removal_mode 0)
			)
			(polygon
				(pts
					(xy 372.377716 -59.924442) (xy 372.885716 -59.924442) (xy 372.885716 -59.543442) (xy 372.377716 -59.543442)
				)
			)
		)
		(zone
			(layer "B.Cu")
			(hatch none 0.5)
			(connect_pads
				(clearance 0)
			)
			(min_thickness 0.25)
			(keepout
				(tracks allowed)
				(vias not_allowed)
				(pads allowed)
				(copperpour not_allowed)
				(footprints allowed)
			)
			(placement
				(enabled no)
				(sheetname "")
			)
			(fill
				(thermal_gap 0.5)
				(thermal_bridge_width 0.5)
				(island_removal_mode 0)
			)
			(polygon
				(pts
					(xy 372.377716 -59.543442) (xy 372.885716 -59.543442) (xy 372.885716 -59.924442) (xy 372.377716 -59.924442)
				)
			)
		)
	)
)
